# S9S_MB_2U (Grand Teton) — schematic netlist excerpt (pin names and nets, part order shuffled) for the footprints in the layout excerpt that follows; sources: Cadence DE-HDL packaged netlist, KiCad conversion of 03242023_DA0F0TMBIJ0_F0T_Motherboard_J_brd_V01_OCP.brd

PC1274  Q_CAP  1UF 16V 10% X6S  pkg C0402  page 282 : A = SW_P12V_PVCCINFAON_CPU0_FLT ; B = GND
PR1781  Q_RES  3.3 1% CHIP  pkg 0402LF  page 271 : A = SW_PVCCFA_EHV_FIVRA_CPU0_BOOT2 ; B = SW_PVCCFA_EHV_FIVRA_CPU0_BOOT2_

(kicad_pcb
	(version 20260206)
	(generator "pcbnew")
	(generator_version "10.0")
	(general
		(thickness 1.6)
		(legacy_teardrops no)
	)
	(paper "A4")
	(title_block
		(title "03242023_DA0F0TMBIJ0_F0T_Motherboard_J_brd_V01_OCP.brd")
		(comment 1 "Grand Teton / footprints 720-721 of 6105")
	)
	(layers
		(0 "F.Cu" signal "TOP")
		(4 "In1.Cu" signal "GND")
		(6 "In2.Cu" signal "IN1")
		(8 "In3.Cu" signal "GND1")
		(10 "In4.Cu" signal "IN2")
		(12 "In5.Cu" signal "GND2")
		(14 "In6.Cu" signal "IN3")
		(16 "In7.Cu" signal "GND3")
		(18 "In8.Cu" signal "VCC")
		(20 "In9.Cu" signal "VCC1")
		(22 "In10.Cu" signal "GND4")
		(24 "In11.Cu" signal "IN4")
		(26 "In12.Cu" signal "GND5")
		(28 "In13.Cu" signal "IN5")
		(30 "In14.Cu" signal "GND6")
		(32 "In15.Cu" signal "IN6")
		(34 "In16.Cu" signal "GND7")
		(2 "B.Cu" signal "BOTTOM")
		(9 "F.Adhes" user "F.Adhesive")
		(11 "B.Adhes" user "B.Adhesive")
		(13 "F.Paste" user "Package Geometry/Pastemask Top")
		(15 "B.Paste" user "Package Geometry/Pastemask Bottom")
		(5 "F.SilkS" user "Ref Des/Silkscreen Top")
		(7 "B.SilkS" user "Ref Des/Silkscreen Bottom")
		(1 "F.Mask" user "Board Geometry/Soldermask Top")
		(3 "B.Mask" user "Board Geometry/Soldermask Bottom")
		(17 "Dwgs.User" user "User.Drawings")
		(19 "Cmts.User" user "User.Comments")
		(21 "Eco1.User" user "User.Eco1")
		(23 "Eco2.User" user "User.Eco2")
		(25 "Edge.Cuts" user "Board Geometry/Outline")
		(27 "Margin" user)
		(31 "F.CrtYd" user "Package Geometry/Place Bound Top")
		(29 "B.CrtYd" user "Package Geometry/Place Bound Bottom")
		(35 "F.Fab" user "Ref Des/Assembly Top")
		(33 "B.Fab" user "Ref Des/Assembly Bottom")
	)
	(footprint ""
		(layer "F.Cu")
		(at 430.642522 -181.57063 90)
		(property "Reference" "PC1274"
			(at 0 0 90)
			(layer "F.SilkS")
			(hide yes)
			(effects
				(font
					(size 1.27 1.27)
				)
			)
		)
		(property "Value" ""
			(at 0 0 90)
			(layer "F.Fab")
			(effects
				(font
					(size 1.27 1.27)
				)
			)
		)
		(duplicate_pad_numbers_are_jumpers no)
		(fp_line
			(start 0.7874 -0.4064)
			(end 0.7874 0.4064)
			(stroke
				(width 0.1524)
				(type default)
			)
			(layer "F.SilkS")
		)
		(fp_line
			(start -0.7874 -0.4064)
			(end 0.7874 -0.4064)
			(stroke
				(width 0.1524)
				(type default)
			)
			(layer "F.SilkS")
		)
		(fp_line
			(start 0.7874 0.4064)
			(end -0.7874 0.4064)
			(stroke
				(width 0.1524)
				(type default)
			)
			(layer "F.SilkS")
		)
		(fp_line
			(start -0.7874 0.4064)
			(end -0.7874 -0.4064)
			(stroke
				(width 0.1524)
				(type default)
			)
			(layer "F.SilkS")
		)
		(fp_line
			(start -0.12065 -0.305054)
			(end -0.12065 -0.2794)
			(stroke
				(width 0.1)
				(type default)
			)
			(layer "F.Fab")
		)
		(fp_line
			(start -0.67945 -0.305054)
			(end -0.12065 -0.305054)
			(stroke
				(width 0.1)
				(type default)
			)
			(layer "F.Fab")
		)
		(fp_line
			(start 0.67945 -0.3048)
			(end 0.67945 0.3048)
			(stroke
				(width 0.1)
				(type default)
			)
			(layer "F.Fab")
		)
		(fp_line
			(start 0.12065 -0.3048)
			(end 0.67945 -0.3048)
			(stroke
				(width 0.1)
				(type default)
			)
			(layer "F.Fab")
		)
		(fp_line
			(start 0.12065 -0.2794)
			(end 0.12065 -0.3048)
			(stroke
				(width 0.1)
				(type default)
			)
			(layer "F.Fab")
		)
		(fp_line
			(start -0.12065 -0.2794)
			(end 0.12065 -0.2794)
			(stroke
				(width 0.1)
				(type default)
			)
			(layer "F.Fab")
		)
		(fp_line
			(start 0.120396 0.2794)
			(end -0.12065 0.2794)
			(stroke
				(width 0.1)
				(type default)
			)
			(layer "F.Fab")
		)
		(fp_line
			(start -0.12065 0.2794)
			(end -0.12065 0.3048)
			(stroke
				(width 0.1)
				(type default)
			)
			(layer "F.Fab")
		)
		(fp_line
			(start 0.67945 0.3048)
			(end 0.120396 0.3048)
			(stroke
				(width 0.1)
				(type default)
			)
			(layer "F.Fab")
		)
		(fp_line
			(start 0.120396 0.3048)
			(end 0.120396 0.2794)
			(stroke
				(width 0.1)
				(type default)
			)
			(layer "F.Fab")
		)
		(fp_line
			(start -0.12065 0.3048)
			(end -0.67945 0.3048)
			(stroke
				(width 0.1)
				(type default)
			)
			(layer "F.Fab")
		)
		(fp_line
			(start -0.67945 0.3048)
			(end -0.67945 -0.305054)
			(stroke
				(width 0.1)
				(type default)
			)
			(layer "F.Fab")
		)
		(pad "1" smd circle
			(at -0.40005 0 90)
			(size 0 0)
			(layers "F.Cu" "F.Mask" "F.Paste")
			(net "SW_P12V_PVCCINFAON_CPU0_FLT")
		)
		(pad "2" smd circle
			(at 0.40005 0 90)
			(size 0 0)
			(layers "F.Cu" "F.Mask" "F.Paste")
			(net "GND")
		)
	)
	(footprint ""
		(layer "F.Cu")
		(at 299.23359 -367.378996 90)
		(property "Reference" "PR1781"
			(at 0 0 90)
			(layer "F.SilkS")
			(hide yes)
			(effects
				(font
					(size 1.27 1.27)
				)
			)
		)
		(property "Value" ""
			(at 0 0 90)
			(layer "F.Fab")
			(effects
				(font
					(size 1.27 1.27)
				)
			)
		)
		(duplicate_pad_numbers_are_jumpers no)
		(fp_line
			(start 0.7874 -0.4064)
			(end 0.7874 0.4064)
			(stroke
				(width 0.1524)
				(type default)
			)
			(layer "F.SilkS")
		)
		(fp_line
			(start -0.7874 -0.4064)
			(end 0.7874 -0.4064)
			(stroke
				(width 0.1524)
				(type default)
			)
			(layer "F.SilkS")
		)
		(fp_line
			(start 0.7874 0.4064)
			(end -0.7874 0.4064)
			(stroke
				(width 0.1524)
				(type default)
			)
			(layer "F.SilkS")
		)
		(fp_line
			(start -0.7874 0.4064)
			(end -0.7874 -0.4064)
			(stroke
				(width 0.1524)
				(type default)
			)
			(layer "F.SilkS")
		)
		(fp_line
			(start -0.12065 -0.305054)
			(end -0.12065 -0.2794)
			(stroke
				(width 0.1)
				(type default)
			)
			(layer "F.Fab")
		)
		(fp_line
			(start -0.67945 -0.305054)
			(end -0.12065 -0.305054)
			(stroke
				(width 0.1)
				(type default)
			)
			(layer "F.Fab")
		)
		(fp_line
			(start 0.67945 -0.3048)
			(end 0.67945 0.3048)
			(stroke
				(width 0.1)
				(type default)
			)
			(layer "F.Fab")
		)
		(fp_line
			(start 0.12065 -0.3048)
			(end 0.67945 -0.3048)
			(stroke
				(width 0.1)
				(type default)
			)
			(layer "F.Fab")
		)
		(fp_line
			(start 0.12065 -0.2794)
			(end 0.12065 -0.3048)
			(stroke
				(width 0.1)
				(type default)
			)
			(layer "F.Fab")
		)
		(fp_line
			(start -0.12065 -0.2794)
			(end 0.12065 -0.2794)
			(stroke
				(width 0.1)
				(type default)
			)
			(layer "F.Fab")
		)
		(fp_line
			(start 0.120396 0.2794)
			(end -0.12065 0.2794)
			(stroke
				(width 0.1)
				(type default)
			)
			(layer "F.Fab")
		)
		(fp_line
			(start -0.12065 0.2794)
			(end -0.12065 0.3048)
			(stroke
				(width 0.1)
				(type default)
			)
			(layer "F.Fab")
		)
		(fp_line
			(start 0.67945 0.3048)
			(end 0.120396 0.3048)
			(stroke
				(width 0.1)
				(type default)
			)
			(layer "F.Fab")
		)
		(fp_line
			(start 0.120396 0.3048)
			(end 0.120396 0.2794)
			(stroke
				(width 0.1)
				(type default)
			)
			(layer "F.Fab")
		)
		(fp_line
			(start -0.12065 0.3048)
			(end -0.67945 0.3048)
			(stroke
				(width 0.1)
				(type default)
			)
			(layer "F.Fab")
		)
		(fp_line
			(start -0.67945 0.3048)
			(end -0.67945 -0.305054)
			(stroke
				(width 0.1)
				(type default)
			)
			(layer "F.Fab")
		)
		(pad "1" smd circle
			(at -0.40005 0 90)
			(size 0 0)
			(layers "F.Cu" "F.Mask" "F.Paste")
			(net "SW_PVCCFA_EHV_FIVRA_CPU0_BOOT2")
		)
		(pad "2" smd circle
			(at 0.40005 0 90)
			(size 0 0)
			(layers "F.Cu" "F.Mask" "F.Paste")
			(net "SW_PVCCFA_EHV_FIVRA_CPU0_BOOT2_")
		)
	)
)
